# T6G (Grand Teton) — schematic netlist excerpt (pin names and nets, part order shuffled) for the footprints in the layout excerpt that follows; sources: Cadence DE-HDL packaged netlist, KiCad conversion of 04192023_DAF0TMB3IC0_F0TG_MB_C_brd_V02_OCP.brd

R1453  Q_RES  0 5% CHIP  pkg 0402LF  page 151 : A = SMB_CPU_5_SDA ; B = SMB_CPU_5_R1_SDA
R1605  Q_RES  1K 1% CHIP  pkg 0402LF  page 144 : A = PD_M2_0_DEVSLP ; B = GND

(kicad_pcb
	(version 20260206)
	(generator "pcbnew")
	(generator_version "10.0")
	(general
		(thickness 1.6)
		(legacy_teardrops no)
	)
	(paper "A4")
	(title_block
		(title "04192023_DAF0TMB3IC0_F0TG_MB_C_brd_V02_OCP.brd")
		(comment 1 "Grand Teton / footprints 2495-2496 of 8354")
	)
	(layers
		(0 "F.Cu" signal "TOP")
		(4 "In1.Cu" signal "GND")
		(6 "In2.Cu" signal "IN1")
		(8 "In3.Cu" signal "GND1")
		(10 "In4.Cu" signal "IN2")
		(12 "In5.Cu" signal "GND2")
		(14 "In6.Cu" signal "IN3")
		(16 "In7.Cu" signal "GND3")
		(18 "In8.Cu" signal "VCC")
		(20 "In9.Cu" signal "VCC1")
		(22 "In10.Cu" signal "GND4")
		(24 "In11.Cu" signal "IN4")
		(26 "In12.Cu" signal "GND5")
		(28 "In13.Cu" signal "IN5")
		(30 "In14.Cu" signal "GND6")
		(32 "In15.Cu" signal "IN6")
		(34 "In16.Cu" signal "GND7")
		(2 "B.Cu" signal "BOTTOM")
		(9 "F.Adhes" user "F.Adhesive")
		(11 "B.Adhes" user "B.Adhesive")
		(13 "F.Paste" user "Package Geometry/Pastemask Top")
		(15 "B.Paste" user "Package Geometry/Pastemask Bottom")
		(5 "F.SilkS" user "Ref Des/Silkscreen Top")
		(7 "B.SilkS" user "Ref Des/Silkscreen Bottom")
		(1 "F.Mask" user "Board Geometry/Soldermask Top")
		(3 "B.Mask" user "Board Geometry/Soldermask Bottom")
		(17 "Dwgs.User" user "User.Drawings")
		(19 "Cmts.User" user "User.Comments")
		(21 "Eco1.User" user "User.Eco1")
		(23 "Eco2.User" user "User.Eco2")
		(25 "Edge.Cuts" user "Board Geometry/Outline")
		(27 "Margin" user)
		(31 "F.CrtYd" user "Package Geometry/Place Bound Top")
		(29 "B.CrtYd" user "Package Geometry/Place Bound Bottom")
		(35 "F.Fab" user "Ref Des/Assembly Top")
		(33 "B.Fab" user "Ref Des/Assembly Bottom")
	)
	(footprint ""
		(layer "F.Cu")
		(at 193.167 -137.632948 -90)
		(property "Reference" "R1453"
			(at 0 0 270)
			(layer "F.SilkS")
			(hide yes)
			(effects
				(font
					(size 1.27 1.27)
				)
			)
		)
		(property "Value" ""
			(at 0 0 270)
			(layer "F.Fab")
			(effects
				(font
					(size 1.27 1.27)
				)
			)
		)
		(duplicate_pad_numbers_are_jumpers no)
		(fp_line
			(start -0.7874 0.4064)
			(end -0.7874 -0.4064)
			(stroke
				(width 0.1524)
				(type default)
			)
			(layer "F.SilkS")
		)
		(fp_line
			(start 0.7874 0.4064)
			(end -0.7874 0.4064)
			(stroke
				(width 0.1524)
				(type default)
			)
			(layer "F.SilkS")
		)
		(fp_line
			(start -0.7874 -0.4064)
			(end 0.7874 -0.4064)
			(stroke
				(width 0.1524)
				(type default)
			)
			(layer "F.SilkS")
		)
		(fp_line
			(start 0.7874 -0.4064)
			(end 0.7874 0.4064)
			(stroke
				(width 0.1524)
				(type default)
			)
			(layer "F.SilkS")
		)
		(fp_line
			(start -0.67945 0.3048)
			(end -0.67945 -0.305054)
			(stroke
				(width 0.1)
				(type default)
			)
			(layer "F.Fab")
		)
		(fp_line
			(start -0.12065 0.3048)
			(end -0.67945 0.3048)
			(stroke
				(width 0.1)
				(type default)
			)
			(layer "F.Fab")
		)
		(fp_line
			(start 0.120396 0.3048)
			(end 0.120396 0.2794)
			(stroke
				(width 0.1)
				(type default)
			)
			(layer "F.Fab")
		)
		(fp_line
			(start 0.67945 0.3048)
			(end 0.120396 0.3048)
			(stroke
				(width 0.1)
				(type default)
			)
			(layer "F.Fab")
		)
		(fp_line
			(start -0.12065 0.2794)
			(end -0.12065 0.3048)
			(stroke
				(width 0.1)
				(type default)
			)
			(layer "F.Fab")
		)
		(fp_line
			(start 0.120396 0.2794)
			(end -0.12065 0.2794)
			(stroke
				(width 0.1)
				(type default)
			)
			(layer "F.Fab")
		)
		(fp_line
			(start -0.12065 -0.2794)
			(end 0.12065 -0.2794)
			(stroke
				(width 0.1)
				(type default)
			)
			(layer "F.Fab")
		)
		(fp_line
			(start 0.12065 -0.2794)
			(end 0.12065 -0.3048)
			(stroke
				(width 0.1)
				(type default)
			)
			(layer "F.Fab")
		)
		(fp_line
			(start 0.12065 -0.3048)
			(end 0.67945 -0.3048)
			(stroke
				(width 0.1)
				(type default)
			)
			(layer "F.Fab")
		)
		(fp_line
			(start 0.67945 -0.3048)
			(end 0.67945 0.3048)
			(stroke
				(width 0.1)
				(type default)
			)
			(layer "F.Fab")
		)
		(fp_line
			(start -0.67945 -0.305054)
			(end -0.12065 -0.305054)
			(stroke
				(width 0.1)
				(type default)
			)
			(layer "F.Fab")
		)
		(fp_line
			(start -0.12065 -0.305054)
			(end -0.12065 -0.2794)
			(stroke
				(width 0.1)
				(type default)
			)
			(layer "F.Fab")
		)
		(pad "1" smd circle
			(at -0.40005 0 270)
			(size 0 0)
			(layers "F.Cu" "F.Mask" "F.Paste")
			(net "SMB_CPU_5_SDA")
		)
		(pad "2" smd circle
			(at 0.40005 0 270)
			(size 0 0)
			(layers "F.Cu" "F.Mask" "F.Paste")
			(net "SMB_CPU_5_R1_SDA")
		)
	)
	(footprint ""
		(layer "F.Cu")
		(at 164.521134 -46.954948 180)
		(property "Reference" "R1605"
			(at 0 0 180)
			(layer "F.SilkS")
			(hide yes)
			(effects
				(font
					(size 1.27 1.27)
				)
			)
		)
		(property "Value" ""
			(at 0 0 180)
			(layer "F.Fab")
			(effects
				(font
					(size 1.27 1.27)
				)
			)
		)
		(duplicate_pad_numbers_are_jumpers no)
		(fp_line
			(start 0.7874 0.4064)
			(end -0.7874 0.4064)
			(stroke
				(width 0.1524)
				(type default)
			)
			(layer "F.SilkS")
		)
		(fp_line
			(start 0.7874 -0.4064)
			(end 0.7874 0.4064)
			(stroke
				(width 0.1524)
				(type default)
			)
			(layer "F.SilkS")
		)
		(fp_line
			(start -0.7874 0.4064)
			(end -0.7874 -0.4064)
			(stroke
				(width 0.1524)
				(type default)
			)
			(layer "F.SilkS")
		)
		(fp_line
			(start -0.7874 -0.4064)
			(end 0.7874 -0.4064)
			(stroke
				(width 0.1524)
				(type default)
			)
			(layer "F.SilkS")
		)
		(fp_line
			(start 0.67945 0.3048)
			(end 0.120396 0.3048)
			(stroke
				(width 0.1)
				(type default)
			)
			(layer "F.Fab")
		)
		(fp_line
			(start 0.67945 -0.3048)
			(end 0.67945 0.3048)
			(stroke
				(width 0.1)
				(type default)
			)
			(layer "F.Fab")
		)
		(fp_line
			(start 0.12065 -0.2794)
			(end 0.12065 -0.3048)
			(stroke
				(width 0.1)
				(type default)
			)
			(layer "F.Fab")
		)
		(fp_line
			(start 0.12065 -0.3048)
			(end 0.67945 -0.3048)
			(stroke
				(width 0.1)
				(type default)
			)
			(layer "F.Fab")
		)
		(fp_line
			(start 0.120396 0.3048)
			(end 0.120396 0.2794)
			(stroke
				(width 0.1)
				(type default)
			)
			(layer "F.Fab")
		)
		(fp_line
			(start 0.120396 0.2794)
			(end -0.12065 0.2794)
			(stroke
				(width 0.1)
				(type default)
			)
			(layer "F.Fab")
		)
		(fp_line
			(start -0.12065 0.3048)
			(end -0.67945 0.3048)
			(stroke
				(width 0.1)
				(type default)
			)
			(layer "F.Fab")
		)
		(fp_line
			(start -0.12065 0.2794)
			(end -0.12065 0.3048)
			(stroke
				(width 0.1)
				(type default)
			)
			(layer "F.Fab")
		)
		(fp_line
			(start -0.12065 -0.2794)
			(end 0.12065 -0.2794)
			(stroke
				(width 0.1)
				(type default)
			)
			(layer "F.Fab")
		)
		(fp_line
			(start -0.12065 -0.305054)
			(end -0.12065 -0.2794)
			(stroke
				(width 0.1)
				(type default)
			)
			(layer "F.Fab")
		)
		(fp_line
			(start -0.67945 0.3048)
			(end -0.67945 -0.305054)
			(stroke
				(width 0.1)
				(type default)
			)
			(layer "F.Fab")
		)
		(fp_line
			(start -0.67945 -0.305054)
			(end -0.12065 -0.305054)
			(stroke
				(width 0.1)
				(type default)
			)
			(layer "F.Fab")
		)
		(pad "1" smd circle
			(at -0.40005 0 180)
			(size 0 0)
			(layers "F.Cu" "F.Mask" "F.Paste")
			(net "PD_M2_0_DEVSLP")
		)
		(pad "2" smd circle
			(at 0.40005 0 180)
			(size 0 0)
			(layers "F.Cu" "F.Mask" "F.Paste")
			(net "GND")
		)
	)
)
